(kicad_pcb
	(version 20260206)
	(generator "pcbnew")
	(generator_version "10.0")
	(general
		(thickness 1.6)
		(legacy_teardrops no)
	)
	(paper "A4")
	(title_block
		(title "01162023_DA0F0TEBIF0_F0T_Expander_BD_F_brd_V02_OCP.brd")
		(comment 1 "Grand Teton / footprints 5923-5929 of 9728")
	)
	(layers
		(0 "F.Cu" signal "TOP")
		(4 "In1.Cu" signal "GND")
		(6 "In2.Cu" signal "VCC")
		(8 "In3.Cu" signal "VCC1")
		(10 "In4.Cu" signal "GND1")
		(12 "In5.Cu" signal "IN1")
		(14 "In6.Cu" signal "GND2")
		(16 "In7.Cu" signal "IN2")
		(18 "In8.Cu" signal "GND3")
		(20 "In9.Cu" signal "IN3")
		(22 "In10.Cu" signal "GND4")
		(24 "In11.Cu" signal "IN4")
		(26 "In12.Cu" signal "GND5")
		(28 "In13.Cu" signal "IN5")
		(30 "In14.Cu" signal "GND6")
		(32 "In15.Cu" signal "IN6")
		(34 "In16.Cu" signal "GND7")
		(2 "B.Cu" signal "BOTTOM")
		(9 "F.Adhes" user "F.Adhesive")
		(11 "B.Adhes" user "B.Adhesive")
		(13 "F.Paste" user "Package Geometry/Pastemask Top")
		(15 "B.Paste" user "Package Geometry/Pastemask Bottom")
		(5 "F.SilkS" user "Ref Des/Silkscreen Top")
		(7 "B.SilkS" user "Ref Des/Silkscreen Bottom")
		(1 "F.Mask" user "Board Geometry/Soldermask Top")
		(3 "B.Mask" user "Board Geometry/Soldermask Bottom")
		(17 "Dwgs.User" user "User.Drawings")
		(19 "Cmts.User" user "User.Comments")
		(21 "Eco1.User" user "User.Eco1")
		(23 "Eco2.User" user "User.Eco2")
		(25 "Edge.Cuts" user "Board Geometry/Outline")
		(27 "Margin" user)
		(31 "F.CrtYd" user "Package Geometry/Place Bound Top")
		(29 "B.CrtYd" user "Package Geometry/Place Bound Bottom")
		(35 "F.Fab" user "Ref Des/Assembly Top")
		(33 "B.Fab" user "Ref Des/Assembly Bottom")
	)
	(footprint ""
		(layer "F.Cu")
		(at 363.998002 -122.780552)
		(property "Reference" "PC462"
			(at 0 0 0)
			(layer "F.SilkS")
			(hide yes)
			(effects
				(font
					(size 1.27 1.27)
				)
			)
		)
		(property "Value" ""
			(at 0 0 0)
			(layer "F.Fab")
			(effects
				(font
					(size 1.27 1.27)
				)
			)
		)
		(duplicate_pad_numbers_are_jumpers no)
		(fp_line
			(start -0.7874 -0.4064)
			(end 0.7874 -0.4064)
			(stroke
				(width 0.1524)
				(type default)
			)
			(layer "F.SilkS")
		)
		(fp_line
			(start -0.7874 0.4064)
			(end -0.7874 -0.4064)
			(stroke
				(width 0.1524)
				(type default)
			)
			(layer "F.SilkS")
		)
		(fp_line
			(start 0.7874 -0.4064)
			(end 0.7874 0.4064)
			(stroke
				(width 0.1524)
				(type default)
			)
			(layer "F.SilkS")
		)
		(fp_line
			(start 0.7874 0.4064)
			(end -0.7874 0.4064)
			(stroke
				(width 0.1524)
				(type default)
			)
			(layer "F.SilkS")
		)
		(fp_line
			(start -0.67945 -0.305054)
			(end -0.12065 -0.305054)
			(stroke
				(width 0.1)
				(type default)
			)
			(layer "F.Fab")
		)
		(fp_line
			(start -0.67945 0.3048)
			(end -0.67945 -0.305054)
			(stroke
				(width 0.1)
				(type default)
			)
			(layer "F.Fab")
		)
		(fp_line
			(start -0.12065 -0.305054)
			(end -0.12065 -0.2794)
			(stroke
				(width 0.1)
				(type default)
			)
			(layer "F.Fab")
		)
		(fp_line
			(start -0.12065 -0.2794)
			(end 0.12065 -0.2794)
			(stroke
				(width 0.1)
				(type default)
			)
			(layer "F.Fab")
		)
		(fp_line
			(start -0.12065 0.2794)
			(end -0.12065 0.3048)
			(stroke
				(width 0.1)
				(type default)
			)
			(layer "F.Fab")
		)
		(fp_line
			(start -0.12065 0.3048)
			(end -0.67945 0.3048)
			(stroke
				(width 0.1)
				(type default)
			)
			(layer "F.Fab")
		)
		(fp_line
			(start 0.120396 0.2794)
			(end -0.12065 0.2794)
			(stroke
				(width 0.1)
				(type default)
			)
			(layer "F.Fab")
		)
		(fp_line
			(start 0.120396 0.3048)
			(end 0.120396 0.2794)
			(stroke
				(width 0.1)
				(type default)
			)
			(layer "F.Fab")
		)
		(fp_line
			(start 0.12065 -0.3048)
			(end 0.67945 -0.3048)
			(stroke
				(width 0.1)
				(type default)
			)
			(layer "F.Fab")
		)
		(fp_line
			(start 0.12065 -0.2794)
			(end 0.12065 -0.3048)
			(stroke
				(width 0.1)
				(type default)
			)
			(layer "F.Fab")
		)
		(fp_line
			(start 0.67945 -0.3048)
			(end 0.67945 0.3048)
			(stroke
				(width 0.1)
				(type default)
			)
			(layer "F.Fab")
		)
		(fp_line
			(start 0.67945 0.3048)
			(end 0.120396 0.3048)
			(stroke
				(width 0.1)
				(type default)
			)
			(layer "F.Fab")
		)
		(pad "1" smd circle
			(at -0.40005 0)
			(size 0 0)
			(layers "F.Cu" "F.Mask" "F.Paste")
			(net "P3V3_AUX")
		)
		(pad "2" smd circle
			(at 0.40005 0)
			(size 0 0)
			(layers "F.Cu" "F.Mask" "F.Paste")
			(net "GND")
		)
	)
	(footprint ""
		(layer "F.Cu")
		(at 26.243788 -49.95291 180)
		(property "Reference" "R511"
			(at 0 0 180)
			(layer "F.SilkS")
			(hide yes)
			(effects
				(font
					(size 1.27 1.27)
				)
			)
		)
		(property "Value" ""
			(at 0 0 180)
			(layer "F.Fab")
			(effects
				(font
					(size 1.27 1.27)
				)
			)
		)
		(duplicate_pad_numbers_are_jumpers no)
		(fp_line
			(start 0.7874 0.4064)
			(end -0.7874 0.4064)
			(stroke
				(width 0.1524)
				(type default)
			)
			(layer "F.SilkS")
		)
		(fp_line
			(start 0.7874 -0.4064)
			(end 0.7874 0.4064)
			(stroke
				(width 0.1524)
				(type default)
			)
			(layer "F.SilkS")
		)
		(fp_line
			(start -0.7874 0.4064)
			(end -0.7874 -0.4064)
			(stroke
				(width 0.1524)
				(type default)
			)
			(layer "F.SilkS")
		)
		(fp_line
			(start -0.7874 -0.4064)
			(end 0.7874 -0.4064)
			(stroke
				(width 0.1524)
				(type default)
			)
			(layer "F.SilkS")
		)
		(fp_line
			(start 0.67945 0.3048)
			(end 0.120396 0.3048)
			(stroke
				(width 0.1)
				(type default)
			)
			(layer "F.Fab")
		)
		(fp_line
			(start 0.67945 -0.3048)
			(end 0.67945 0.3048)
			(stroke
				(width 0.1)
				(type default)
			)
			(layer "F.Fab")
		)
		(fp_line
			(start 0.12065 -0.2794)
			(end 0.12065 -0.3048)
			(stroke
				(width 0.1)
				(type default)
			)
			(layer "F.Fab")
		)
		(fp_line
			(start 0.12065 -0.3048)
			(end 0.67945 -0.3048)
			(stroke
				(width 0.1)
				(type default)
			)
			(layer "F.Fab")
		)
		(fp_line
			(start 0.120396 0.3048)
			(end 0.120396 0.2794)
			(stroke
				(width 0.1)
				(type default)
			)
			(layer "F.Fab")
		)
		(fp_line
			(start 0.120396 0.2794)
			(end -0.12065 0.2794)
			(stroke
				(width 0.1)
				(type default)
			)
			(layer "F.Fab")
		)
		(fp_line
			(start -0.12065 0.3048)
			(end -0.67945 0.3048)
			(stroke
				(width 0.1)
				(type default)
			)
			(layer "F.Fab")
		)
		(fp_line
			(start -0.12065 0.2794)
			(end -0.12065 0.3048)
			(stroke
				(width 0.1)
				(type default)
			)
			(layer "F.Fab")
		)
		(fp_line
			(start -0.12065 -0.2794)
			(end 0.12065 -0.2794)
			(stroke
				(width 0.1)
				(type default)
			)
			(layer "F.Fab")
		)
		(fp_line
			(start -0.12065 -0.305054)
			(end -0.12065 -0.2794)
			(stroke
				(width 0.1)
				(type default)
			)
			(layer "F.Fab")
		)
		(fp_line
			(start -0.67945 0.3048)
			(end -0.67945 -0.305054)
			(stroke
				(width 0.1)
				(type default)
			)
			(layer "F.Fab")
		)
		(fp_line
			(start -0.67945 -0.305054)
			(end -0.12065 -0.305054)
			(stroke
				(width 0.1)
				(type default)
			)
			(layer "F.Fab")
		)
		(pad "1" smd circle
			(at -0.40005 0 180)
			(size 0 0)
			(layers "F.Cu" "F.Mask" "F.Paste")
			(net "SMB_BIC_I2C6_MUX_SSD_0_7_ADC_R_SCL")
		)
		(pad "2" smd circle
			(at 0.40005 0 180)
			(size 0 0)
			(layers "F.Cu" "F.Mask" "F.Paste")
			(net "SMB_SSD0_ADC_SCL")
		)
	)
	(footprint ""
		(layer "F.Cu")
		(at 435.055772 -343.952322 90)
		(property "Reference" "C803"
			(at 0 0 90)
			(layer "F.SilkS")
			(hide yes)
			(effects
				(font
					(size 1.27 1.27)
				)
			)
		)
		(property "Value" ""
			(at 0 0 90)
			(layer "F.Fab")
			(effects
				(font
					(size 1.27 1.27)
				)
			)
		)
		(duplicate_pad_numbers_are_jumpers no)
		(fp_line
			(start 0.299974 -0.150114)
			(end 0.299974 0.150114)
			(stroke
				(width 0.1)
				(type default)
			)
			(layer "F.Fab")
		)
		(fp_line
			(start -0.299974 -0.150114)
			(end 0.299974 -0.150114)
			(stroke
				(width 0.1)
				(type default)
			)
			(layer "F.Fab")
		)
		(fp_line
			(start 0.299974 0.150114)
			(end -0.299974 0.150114)
			(stroke
				(width 0.1)
				(type default)
			)
			(layer "F.Fab")
		)
		(fp_line
			(start -0.299974 0.150114)
			(end -0.299974 -0.150114)
			(stroke
				(width 0.1)
				(type default)
			)
			(layer "F.Fab")
		)
		(pad "1" smd rect
			(at -0.2667 0 90)
			(size 0.3048 0.381)
			(layers "F.Cu" "F.Mask" "F.Paste")
			(net "P5E_PEX3_STN7_TX_DN<123>")
		)
		(pad "2" smd rect
			(at 0.2667 0 90)
			(size 0.3048 0.381)
			(layers "F.Cu" "F.Mask" "F.Paste")
			(net "P5E_PEX3_STN7_TX_C_DN<123>")
		)
	)
	(footprint ""
		(layer "F.Cu")
		(at 16.785336 -277.280624 180)
		(property "Reference" "R776"
			(at 0 0 180)
			(layer "F.SilkS")
			(hide yes)
			(effects
				(font
					(size 1.27 1.27)
				)
			)
		)
		(property "Value" ""
			(at 0 0 180)
			(layer "F.Fab")
			(effects
				(font
					(size 1.27 1.27)
				)
			)
		)
		(duplicate_pad_numbers_are_jumpers no)
		(fp_line
			(start 0.7874 0.4064)
			(end -0.7874 0.4064)
			(stroke
				(width 0.1524)
				(type default)
			)
			(layer "F.SilkS")
		)
		(fp_line
			(start 0.7874 -0.4064)
			(end 0.7874 0.4064)
			(stroke
				(width 0.1524)
				(type default)
			)
			(layer "F.SilkS")
		)
		(fp_line
			(start -0.7874 0.4064)
			(end -0.7874 -0.4064)
			(stroke
				(width 0.1524)
				(type default)
			)
			(layer "F.SilkS")
		)
		(fp_line
			(start -0.7874 -0.4064)
			(end 0.7874 -0.4064)
			(stroke
				(width 0.1524)
				(type default)
			)
			(layer "F.SilkS")
		)
		(fp_line
			(start 0.67945 0.3048)
			(end 0.120396 0.3048)
			(stroke
				(width 0.1)
				(type default)
			)
			(layer "F.Fab")
		)
		(fp_line
			(start 0.67945 -0.3048)
			(end 0.67945 0.3048)
			(stroke
				(width 0.1)
				(type default)
			)
			(layer "F.Fab")
		)
		(fp_line
			(start 0.12065 -0.2794)
			(end 0.12065 -0.3048)
			(stroke
				(width 0.1)
				(type default)
			)
			(layer "F.Fab")
		)
		(fp_line
			(start 0.12065 -0.3048)
			(end 0.67945 -0.3048)
			(stroke
				(width 0.1)
				(type default)
			)
			(layer "F.Fab")
		)
		(fp_line
			(start 0.120396 0.3048)
			(end 0.120396 0.2794)
			(stroke
				(width 0.1)
				(type default)
			)
			(layer "F.Fab")
		)
		(fp_line
			(start 0.120396 0.2794)
			(end -0.12065 0.2794)
			(stroke
				(width 0.1)
				(type default)
			)
			(layer "F.Fab")
		)
		(fp_line
			(start -0.12065 0.3048)
			(end -0.67945 0.3048)
			(stroke
				(width 0.1)
				(type default)
			)
			(layer "F.Fab")
		)
		(fp_line
			(start -0.12065 0.2794)
			(end -0.12065 0.3048)
			(stroke
				(width 0.1)
				(type default)
			)
			(layer "F.Fab")
		)
		(fp_line
			(start -0.12065 -0.2794)
			(end 0.12065 -0.2794)
			(stroke
				(width 0.1)
				(type default)
			)
			(layer "F.Fab")
		)
		(fp_line
			(start -0.12065 -0.305054)
			(end -0.12065 -0.2794)
			(stroke
				(width 0.1)
				(type default)
			)
			(layer "F.Fab")
		)
		(fp_line
			(start -0.67945 0.3048)
			(end -0.67945 -0.305054)
			(stroke
				(width 0.1)
				(type default)
			)
			(layer "F.Fab")
		)
		(fp_line
			(start -0.67945 -0.305054)
			(end -0.12065 -0.305054)
			(stroke
				(width 0.1)
				(type default)
			)
			(layer "F.Fab")
		)
		(pad "1" smd circle
			(at -0.40005 0 180)
			(size 0 0)
			(layers "F.Cu" "F.Mask" "F.Paste")
			(net "SMB_BIC_I2C6_MUX_PEX_ADC_R_SDA")
		)
		(pad "2" smd circle
			(at 0.40005 0 180)
			(size 0 0)
			(layers "F.Cu" "F.Mask" "F.Paste")
			(net "SMB_PEX0_P1V25_ADC_SDA")
		)
	)
	(footprint ""
		(layer "F.Cu")
		(at 214.884 -228.6 -90)
		(property "Reference" "R6305"
			(at 0 0 270)
			(layer "F.SilkS")
			(hide yes)
			(effects
				(font
					(size 1.27 1.27)
				)
			)
		)
		(property "Value" ""
			(at 0 0 270)
			(layer "F.Fab")
			(effects
				(font
					(size 1.27 1.27)
				)
			)
		)
		(duplicate_pad_numbers_are_jumpers no)
		(fp_line
			(start -0.7874 0.4064)
			(end -0.7874 -0.4064)
			(stroke
				(width 0.1524)
				(type default)
			)
			(layer "F.SilkS")
		)
		(fp_line
			(start 0.7874 0.4064)
			(end -0.7874 0.4064)
			(stroke
				(width 0.1524)
				(type default)
			)
			(layer "F.SilkS")
		)
		(fp_line
			(start -0.7874 -0.4064)
			(end 0.7874 -0.4064)
			(stroke
				(width 0.1524)
				(type default)
			)
			(layer "F.SilkS")
		)
		(fp_line
			(start 0.7874 -0.4064)
			(end 0.7874 0.4064)
			(stroke
				(width 0.1524)
				(type default)
			)
			(layer "F.SilkS")
		)
		(fp_line
			(start -0.67945 0.3048)
			(end -0.67945 -0.305054)
			(stroke
				(width 0.1)
				(type default)
			)
			(layer "F.Fab")
		)
		(fp_line
			(start -0.12065 0.3048)
			(end -0.67945 0.3048)
			(stroke
				(width 0.1)
				(type default)
			)
			(layer "F.Fab")
		)
		(fp_line
			(start 0.120396 0.3048)
			(end 0.120396 0.2794)
			(stroke
				(width 0.1)
				(type default)
			)
			(layer "F.Fab")
		)
		(fp_line
			(start 0.67945 0.3048)
			(end 0.120396 0.3048)
			(stroke
				(width 0.1)
				(type default)
			)
			(layer "F.Fab")
		)
		(fp_line
			(start -0.12065 0.2794)
			(end -0.12065 0.3048)
			(stroke
				(width 0.1)
				(type default)
			)
			(layer "F.Fab")
		)
		(fp_line
			(start 0.120396 0.2794)
			(end -0.12065 0.2794)
			(stroke
				(width 0.1)
				(type default)
			)
			(layer "F.Fab")
		)
		(fp_line
			(start -0.12065 -0.2794)
			(end 0.12065 -0.2794)
			(stroke
				(width 0.1)
				(type default)
			)
			(layer "F.Fab")
		)
		(fp_line
			(start 0.12065 -0.2794)
			(end 0.12065 -0.3048)
			(stroke
				(width 0.1)
				(type default)
			)
			(layer "F.Fab")
		)
		(fp_line
			(start 0.12065 -0.3048)
			(end 0.67945 -0.3048)
			(stroke
				(width 0.1)
				(type default)
			)
			(layer "F.Fab")
		)
		(fp_line
			(start 0.67945 -0.3048)
			(end 0.67945 0.3048)
			(stroke
				(width 0.1)
				(type default)
			)
			(layer "F.Fab")
		)
		(fp_line
			(start -0.67945 -0.305054)
			(end -0.12065 -0.305054)
			(stroke
				(width 0.1)
				(type default)
			)
			(layer "F.Fab")
		)
		(fp_line
			(start -0.12065 -0.305054)
			(end -0.12065 -0.2794)
			(stroke
				(width 0.1)
				(type default)
			)
			(layer "F.Fab")
		)
		(pad "1" smd circle
			(at -0.40005 0 270)
			(size 0 0)
			(layers "F.Cu" "F.Mask" "F.Paste")
			(net "PRSNT_DBV2_SLIMSAS_R")
		)
		(pad "2" smd circle
			(at 0.40005 0 270)
			(size 0 0)
			(layers "F.Cu" "F.Mask" "F.Paste")
			(net "GND")
		)
	)
	(footprint ""
		(layer "F.Cu")
		(at 226.546664 -204.44206 90)
		(property "Reference" "R5279"
			(at 0 0 90)
			(layer "F.SilkS")
			(hide yes)
			(effects
				(font
					(size 1.27 1.27)
				)
			)
		)
		(property "Value" ""
			(at 0 0 90)
			(layer "F.Fab")
			(effects
				(font
					(size 1.27 1.27)
				)
			)
		)
		(duplicate_pad_numbers_are_jumpers no)
		(fp_line
			(start 0.7874 -0.4064)
			(end 0.7874 0.4064)
			(stroke
				(width 0.1524)
				(type default)
			)
			(layer "F.SilkS")
		)
		(fp_line
			(start -0.7874 -0.4064)
			(end 0.7874 -0.4064)
			(stroke
				(width 0.1524)
				(type default)
			)
			(layer "F.SilkS")
		)
		(fp_line
			(start 0.7874 0.4064)
			(end -0.7874 0.4064)
			(stroke
				(width 0.1524)
				(type default)
			)
			(layer "F.SilkS")
		)
		(fp_line
			(start -0.7874 0.4064)
			(end -0.7874 -0.4064)
			(stroke
				(width 0.1524)
				(type default)
			)
			(layer "F.SilkS")
		)
		(fp_line
			(start -0.12065 -0.305054)
			(end -0.12065 -0.2794)
			(stroke
				(width 0.1)
				(type default)
			)
			(layer "F.Fab")
		)
		(fp_line
			(start -0.67945 -0.305054)
			(end -0.12065 -0.305054)
			(stroke
				(width 0.1)
				(type default)
			)
			(layer "F.Fab")
		)
		(fp_line
			(start 0.67945 -0.3048)
			(end 0.67945 0.3048)
			(stroke
				(width 0.1)
				(type default)
			)
			(layer "F.Fab")
		)
		(fp_line
			(start 0.12065 -0.3048)
			(end 0.67945 -0.3048)
			(stroke
				(width 0.1)
				(type default)
			)
			(layer "F.Fab")
		)
		(fp_line
			(start 0.12065 -0.2794)
			(end 0.12065 -0.3048)
			(stroke
				(width 0.1)
				(type default)
			)
			(layer "F.Fab")
		)
		(fp_line
			(start -0.12065 -0.2794)
			(end 0.12065 -0.2794)
			(stroke
				(width 0.1)
				(type default)
			)
			(layer "F.Fab")
		)
		(fp_line
			(start 0.120396 0.2794)
			(end -0.12065 0.2794)
			(stroke
				(width 0.1)
				(type default)
			)
			(layer "F.Fab")
		)
		(fp_line
			(start -0.12065 0.2794)
			(end -0.12065 0.3048)
			(stroke
				(width 0.1)
				(type default)
			)
			(layer "F.Fab")
		)
		(fp_line
			(start 0.67945 0.3048)
			(end 0.120396 0.3048)
			(stroke
				(width 0.1)
				(type default)
			)
			(layer "F.Fab")
		)
		(fp_line
			(start 0.120396 0.3048)
			(end 0.120396 0.2794)
			(stroke
				(width 0.1)
				(type default)
			)
			(layer "F.Fab")
		)
		(fp_line
			(start -0.12065 0.3048)
			(end -0.67945 0.3048)
			(stroke
				(width 0.1)
				(type default)
			)
			(layer "F.Fab")
		)
		(fp_line
			(start -0.67945 0.3048)
			(end -0.67945 -0.305054)
			(stroke
				(width 0.1)
				(type default)
			)
			(layer "F.Fab")
		)
		(pad "1" smd circle
			(at -0.40005 0 90)
			(size 0 0)
			(layers "F.Cu" "F.Mask" "F.Paste")
			(net "JTAG_BIC_TDI_R")
		)
		(pad "2" smd circle
			(at 0.40005 0 90)
			(size 0 0)
			(layers "F.Cu" "F.Mask" "F.Paste")
			(net "JTAG_BIC_TDI")
		)
	)
	(footprint ""
		(layer "F.Cu")
		(at 196.639434 -158.219648)
		(property "Reference" "R161"
			(at 0 0 0)
			(layer "F.SilkS")
			(hide yes)
			(effects
				(font
					(size 1.27 1.27)
				)
			)
		)
		(property "Value" ""
			(at 0 0 0)
			(layer "F.Fab")
			(effects
				(font
					(size 1.27 1.27)
				)
			)
		)
		(duplicate_pad_numbers_are_jumpers no)
		(fp_line
			(start -0.7874 -0.4064)
			(end 0.7874 -0.4064)
			(stroke
				(width 0.1524)
				(type default)
			)
			(layer "F.SilkS")
		)
		(fp_line
			(start -0.7874 0.4064)
			(end -0.7874 -0.4064)
			(stroke
				(width 0.1524)
				(type default)
			)
			(layer "F.SilkS")
		)
		(fp_line
			(start 0.7874 -0.4064)
			(end 0.7874 0.4064)
			(stroke
				(width 0.1524)
				(type default)
			)
			(layer "F.SilkS")
		)
		(fp_line
			(start 0.7874 0.4064)
			(end -0.7874 0.4064)
			(stroke
				(width 0.1524)
				(type default)
			)
			(layer "F.SilkS")
		)
		(fp_line
			(start -0.67945 -0.305054)
			(end -0.12065 -0.305054)
			(stroke
				(width 0.1)
				(type default)
			)
			(layer "F.Fab")
		)
		(fp_line
			(start -0.67945 0.3048)
			(end -0.67945 -0.305054)
			(stroke
				(width 0.1)
				(type default)
			)
			(layer "F.Fab")
		)
		(fp_line
			(start -0.12065 -0.305054)
			(end -0.12065 -0.2794)
			(stroke
				(width 0.1)
				(type default)
			)
			(layer "F.Fab")
		)
		(fp_line
			(start -0.12065 -0.2794)
			(end 0.12065 -0.2794)
			(stroke
				(width 0.1)
				(type default)
			)
			(layer "F.Fab")
		)
		(fp_line
			(start -0.12065 0.2794)
			(end -0.12065 0.3048)
			(stroke
				(width 0.1)
				(type default)
			)
			(layer "F.Fab")
		)
		(fp_line
			(start -0.12065 0.3048)
			(end -0.67945 0.3048)
			(stroke
				(width 0.1)
				(type default)
			)
			(layer "F.Fab")
		)
		(fp_line
			(start 0.120396 0.2794)
			(end -0.12065 0.2794)
			(stroke
				(width 0.1)
				(type default)
			)
			(layer "F.Fab")
		)
		(fp_line
			(start 0.120396 0.3048)
			(end 0.120396 0.2794)
			(stroke
				(width 0.1)
				(type default)
			)
			(layer "F.Fab")
		)
		(fp_line
			(start 0.12065 -0.3048)
			(end 0.67945 -0.3048)
			(stroke
				(width 0.1)
				(type default)
			)
			(layer "F.Fab")
		)
		(fp_line
			(start 0.12065 -0.2794)
			(end 0.12065 -0.3048)
			(stroke
				(width 0.1)
				(type default)
			)
			(layer "F.Fab")
		)
		(fp_line
			(start 0.67945 -0.3048)
			(end 0.67945 0.3048)
			(stroke
				(width 0.1)
				(type default)
			)
			(layer "F.Fab")
		)
		(fp_line
			(start 0.67945 0.3048)
			(end 0.120396 0.3048)
			(stroke
				(width 0.1)
				(type default)
			)
			(layer "F.Fab")
		)
		(pad "1" smd circle
			(at -0.40005 0)
			(size 0 0)
			(layers "F.Cu" "F.Mask" "F.Paste")
			(net "PRSNTB3_NIC3_N")
		)
		(pad "2" smd circle
			(at 0.40005 0)
			(size 0 0)
			(layers "F.Cu" "F.Mask" "F.Paste")
			(net "P3V3_AUX")
		)
	)
)
